# T6G (Grand Teton) — schematic netlist excerpt (pin names and nets, part order shuffled) for the footprints in the layout excerpt that follows; sources: Cadence DE-HDL packaged netlist, KiCad conversion of 04192023_DAF0TMB3IC0_F0TG_MB_C_brd_V02_OCP.brd

C6655  Q_CAP_DIFFBUS  DIFF BUS_0.22UF 6.3V 20% X6S  pkg C0201  page 319 : \1\ = P5E_CPU1_P0_TX_BUF_C_DP<13> ; \2\ = P5E_CPU1_P0_TX_BUF_DP<13>
C7000  Q_CAPP  470UF 2.5V 20% SPCAP  pkg SMLF  page 279 : A = P0V9_CPU0_RT_2D ; B = GND
R3133  Q_RES  1K 1% CHIP  pkg 0402LF  page 140 : A = P3V3_AUX ; B = OCP_V3_2_PRSNT0_R_N

(kicad_pcb
	(version 20260206)
	(generator "pcbnew")
	(generator_version "10.0")
	(general
		(thickness 1.6)
		(legacy_teardrops no)
	)
	(paper "A4")
	(title_block
		(title "04192023_DAF0TMB3IC0_F0TG_MB_C_brd_V02_OCP.brd")
		(comment 1 "Grand Teton / footprints 3526-3528 of 8354")
	)
	(layers
		(0 "F.Cu" signal "TOP")
		(4 "In1.Cu" signal "GND")
		(6 "In2.Cu" signal "IN1")
		(8 "In3.Cu" signal "GND1")
		(10 "In4.Cu" signal "IN2")
		(12 "In5.Cu" signal "GND2")
		(14 "In6.Cu" signal "IN3")
		(16 "In7.Cu" signal "GND3")
		(18 "In8.Cu" signal "VCC")
		(20 "In9.Cu" signal "VCC1")
		(22 "In10.Cu" signal "GND4")
		(24 "In11.Cu" signal "IN4")
		(26 "In12.Cu" signal "GND5")
		(28 "In13.Cu" signal "IN5")
		(30 "In14.Cu" signal "GND6")
		(32 "In15.Cu" signal "IN6")
		(34 "In16.Cu" signal "GND7")
		(2 "B.Cu" signal "BOTTOM")
		(9 "F.Adhes" user "F.Adhesive")
		(11 "B.Adhes" user "B.Adhesive")
		(13 "F.Paste" user "Package Geometry/Pastemask Top")
		(15 "B.Paste" user "Package Geometry/Pastemask Bottom")
		(5 "F.SilkS" user "Ref Des/Silkscreen Top")
		(7 "B.SilkS" user "Ref Des/Silkscreen Bottom")
		(1 "F.Mask" user "Board Geometry/Soldermask Top")
		(3 "B.Mask" user "Board Geometry/Soldermask Bottom")
		(17 "Dwgs.User" user "User.Drawings")
		(19 "Cmts.User" user "User.Comments")
		(21 "Eco1.User" user "User.Eco1")
		(23 "Eco2.User" user "User.Eco2")
		(25 "Edge.Cuts" user "Board Geometry/Outline")
		(27 "Margin" user)
		(31 "F.CrtYd" user "Package Geometry/Place Bound Top")
		(29 "B.CrtYd" user "Package Geometry/Place Bound Bottom")
		(35 "F.Fab" user "Ref Des/Assembly Top")
		(33 "B.Fab" user "Ref Des/Assembly Bottom")
	)
	(footprint ""
		(layer "F.Cu")
		(at 88.505284 -408.517344 -90)
		(property "Reference" "C6655"
			(at 0 0 270)
			(layer "F.SilkS")
			(hide yes)
			(effects
				(font
					(size 1.27 1.27)
				)
			)
		)
		(property "Value" ""
			(at 0 0 270)
			(layer "F.Fab")
			(effects
				(font
					(size 1.27 1.27)
				)
			)
		)
		(duplicate_pad_numbers_are_jumpers no)
		(fp_line
			(start -0.299974 0.150114)
			(end -0.299974 -0.150114)
			(stroke
				(width 0.1)
				(type default)
			)
			(layer "F.Fab")
		)
		(fp_line
			(start 0.299974 0.150114)
			(end -0.299974 0.150114)
			(stroke
				(width 0.1)
				(type default)
			)
			(layer "F.Fab")
		)
		(fp_line
			(start -0.299974 -0.150114)
			(end 0.299974 -0.150114)
			(stroke
				(width 0.1)
				(type default)
			)
			(layer "F.Fab")
		)
		(fp_line
			(start 0.299974 -0.150114)
			(end 0.299974 0.150114)
			(stroke
				(width 0.1)
				(type default)
			)
			(layer "F.Fab")
		)
		(pad "1" smd rect
			(at -0.2667 0 270)
			(size 0.3048 0.381)
			(layers "F.Cu" "F.Mask" "F.Paste")
			(net "P5E_CPU1_P0_TX_BUF_C_DP<13>")
		)
		(pad "2" smd rect
			(at 0.2667 0 270)
			(size 0.3048 0.381)
			(layers "F.Cu" "F.Mask" "F.Paste")
			(net "P5E_CPU1_P0_TX_BUF_DP<13>")
		)
	)
	(footprint ""
		(layer "F.Cu")
		(at 9.74471 -79.480664)
		(property "Reference" "R3133"
			(at 0 0 0)
			(layer "F.SilkS")
			(hide yes)
			(effects
				(font
					(size 1.27 1.27)
				)
			)
		)
		(property "Value" ""
			(at 0 0 0)
			(layer "F.Fab")
			(effects
				(font
					(size 1.27 1.27)
				)
			)
		)
		(duplicate_pad_numbers_are_jumpers no)
		(fp_line
			(start -0.7874 -0.4064)
			(end 0.7874 -0.4064)
			(stroke
				(width 0.1524)
				(type default)
			)
			(layer "F.SilkS")
		)
		(fp_line
			(start -0.7874 0.4064)
			(end -0.7874 -0.4064)
			(stroke
				(width 0.1524)
				(type default)
			)
			(layer "F.SilkS")
		)
		(fp_line
			(start 0.7874 -0.4064)
			(end 0.7874 0.4064)
			(stroke
				(width 0.1524)
				(type default)
			)
			(layer "F.SilkS")
		)
		(fp_line
			(start 0.7874 0.4064)
			(end -0.7874 0.4064)
			(stroke
				(width 0.1524)
				(type default)
			)
			(layer "F.SilkS")
		)
		(fp_line
			(start -0.67945 -0.305054)
			(end -0.12065 -0.305054)
			(stroke
				(width 0.1)
				(type default)
			)
			(layer "F.Fab")
		)
		(fp_line
			(start -0.67945 0.3048)
			(end -0.67945 -0.305054)
			(stroke
				(width 0.1)
				(type default)
			)
			(layer "F.Fab")
		)
		(fp_line
			(start -0.12065 -0.305054)
			(end -0.12065 -0.2794)
			(stroke
				(width 0.1)
				(type default)
			)
			(layer "F.Fab")
		)
		(fp_line
			(start -0.12065 -0.2794)
			(end 0.12065 -0.2794)
			(stroke
				(width 0.1)
				(type default)
			)
			(layer "F.Fab")
		)
		(fp_line
			(start -0.12065 0.2794)
			(end -0.12065 0.3048)
			(stroke
				(width 0.1)
				(type default)
			)
			(layer "F.Fab")
		)
		(fp_line
			(start -0.12065 0.3048)
			(end -0.67945 0.3048)
			(stroke
				(width 0.1)
				(type default)
			)
			(layer "F.Fab")
		)
		(fp_line
			(start 0.120396 0.2794)
			(end -0.12065 0.2794)
			(stroke
				(width 0.1)
				(type default)
			)
			(layer "F.Fab")
		)
		(fp_line
			(start 0.120396 0.3048)
			(end 0.120396 0.2794)
			(stroke
				(width 0.1)
				(type default)
			)
			(layer "F.Fab")
		)
		(fp_line
			(start 0.12065 -0.3048)
			(end 0.67945 -0.3048)
			(stroke
				(width 0.1)
				(type default)
			)
			(layer "F.Fab")
		)
		(fp_line
			(start 0.12065 -0.2794)
			(end 0.12065 -0.3048)
			(stroke
				(width 0.1)
				(type default)
			)
			(layer "F.Fab")
		)
		(fp_line
			(start 0.67945 -0.3048)
			(end 0.67945 0.3048)
			(stroke
				(width 0.1)
				(type default)
			)
			(layer "F.Fab")
		)
		(fp_line
			(start 0.67945 0.3048)
			(end 0.120396 0.3048)
			(stroke
				(width 0.1)
				(type default)
			)
			(layer "F.Fab")
		)
		(pad "1" smd circle
			(at -0.40005 0)
			(size 0 0)
			(layers "F.Cu" "F.Mask" "F.Paste")
			(net "P3V3_AUX")
		)
		(pad "2" smd circle
			(at 0.40005 0)
			(size 0 0)
			(layers "F.Cu" "F.Mask" "F.Paste")
			(net "OCP_V3_2_PRSNT0_R_N")
		)
	)
	(footprint ""
		(layer "F.Cu")
		(at 323.374512 -409.15082 180)
		(property "Reference" "C7000"
			(at -5.053076 -1.373632 0)
			(unlocked yes)
			(layer "F.SilkS")
			(effects
				(font
					(size 0.7874 0.5842)
					(thickness 0.1524)
				)
				(justify left)
			)
		)
		(property "Value" ""
			(at 0 0 180)
			(layer "F.Fab")
			(effects
				(font
					(size 1.27 1.27)
				)
			)
		)
		(duplicate_pad_numbers_are_jumpers no)
		(fp_line
			(start 4.53898 2.15011)
			(end -4.53898 2.15011)
			(stroke
				(width 0.1524)
				(type default)
			)
			(layer "F.SilkS")
		)
		(fp_line
			(start 4.53898 -2.15011)
			(end 4.53898 2.15011)
			(stroke
				(width 0.1524)
				(type default)
			)
			(layer "F.SilkS")
		)
		(fp_line
			(start -4.53898 2.15011)
			(end -4.53898 -2.15011)
			(stroke
				(width 0.1524)
				(type default)
			)
			(layer "F.SilkS")
		)
		(fp_line
			(start -4.53898 -2.15011)
			(end 4.53898 -2.15011)
			(stroke
				(width 0.1524)
				(type default)
			)
			(layer "F.SilkS")
		)
		(fp_line
			(start -4.53898 -2.150618)
			(end -4.539742 2.152142)
			(stroke
				(width 0.1524)
				(type default)
			)
			(layer "F.SilkS")
		)
		(fp_line
			(start -4.69138 -2.150618)
			(end -4.692396 2.161032)
			(stroke
				(width 0.1524)
				(type default)
			)
			(layer "F.SilkS")
		)
		(fp_line
			(start -4.83108 2.150364)
			(end -4.447794 2.149348)
			(stroke
				(width 0.1524)
				(type default)
			)
			(layer "F.SilkS")
		)
		(fp_line
			(start -4.84378 -2.150618)
			(end -4.53898 -2.150618)
			(stroke
				(width 0.1524)
				(type default)
			)
			(layer "F.SilkS")
		)
		(fp_line
			(start -4.84378 -2.150618)
			(end -4.842256 2.163064)
			(stroke
				(width 0.1524)
				(type default)
			)
			(layer "F.SilkS")
		)
		(fp_line
			(start 3.64998 2.15011)
			(end -3.64998 2.15011)
			(stroke
				(width 0.1)
				(type default)
			)
			(layer "F.Fab")
		)
		(fp_line
			(start 3.64998 -2.15011)
			(end 3.64998 2.15011)
			(stroke
				(width 0.1)
				(type default)
			)
			(layer "F.Fab")
		)
		(fp_line
			(start -3.64998 2.15011)
			(end -3.64998 -2.15011)
			(stroke
				(width 0.1)
				(type default)
			)
			(layer "F.Fab")
		)
		(fp_line
			(start -3.64998 -2.15011)
			(end 3.64998 -2.15011)
			(stroke
				(width 0.1)
				(type default)
			)
			(layer "F.Fab")
		)
		(fp_text user "-"
			(at 6.26745 2.685288 0)
			(unlocked yes)
			(layer "F.SilkS")
			(effects
				(font
					(size 1.905 1.4224)
					(thickness 0.1524)
				)
				(justify left)
			)
		)
		(fp_text user "+"
			(at -4.515612 2.609342 180)
			(unlocked yes)
			(layer "F.SilkS")
			(effects
				(font
					(size 1.905 1.4224)
					(thickness 0.1524)
				)
				(justify left)
			)
		)
		(fp_text user "-"
			(at 4.313174 -0.094488 180)
			(unlocked yes)
			(layer "F.Fab")
			(effects
				(font
					(size 1.905 1.4224)
					(thickness 0.1524)
				)
				(justify left)
			)
		)
		(fp_text user "+"
			(at -6.214872 -0.337058 180)
			(unlocked yes)
			(layer "F.Fab")
			(effects
				(font
					(size 1.905 1.4224)
					(thickness 0.1524)
				)
				(justify left)
			)
		)
		(pad "1" smd rect
			(at -3.199892 0 180)
			(size 2.413 2.8194)
			(layers "F.Cu" "F.Mask" "F.Paste")
			(net "P0V9_CPU0_RT_2D")
		)
		(pad "2" smd rect
			(at 3.199892 0 180)
			(size 2.413 2.8194)
			(layers "F.Cu" "F.Mask" "F.Paste")
			(net "GND")
		)
	)
)
